FILE_TYPE = CONNECTIVITY;
{Allegro Design Entry HDL 16.6-p007 (v16-6-112F) 10/10/2012}
"PAGE_NUMBER" = 22;
0"NC";
1"GND\g";
2"PVCCMCP_CPU0\g";
3"P1V8_MCP_CPU0\g";
4"TP_CPU0_RSVD_288";
5"TP_CPU0_RSVD_219";
6"TP_CPU0_RSVD_248";
7"TP_CPU0_RSVD_211";
8"TP_CPU0_RSVD_223";
9"TP_CPU0_RSVD_298";
10"TP_CPU0_RSVD_217";
11"TP_CPU0_RSVD_218";
12"H_CPU0_FIVR_FAULT_G";
13"CLK_322M_OSC_CPU0_RC_DP";
14"TP_CPU0_RSVD_TEST_5";
15"CPU_XDP_PRESENT_N";
16"TP_CPU0_RSVD_212";
17"CLK_322M_OSC_CPU0_RC_DN";
18"TP_CPU0_RSVD_214";
19"PD_CPU0_DMIMODE_OVERRIDE";
20"TP_CPU0_RSVD_216";
21"XDP_CPU_PWR_DEBUG_N";
22"VSENSE_P1V8MCP_CPU0_SKT_VRTN";
23"TP_CPU0_RSVD_210";
24"TP_CPU0_RSVD_208";
25"CLK_100M_CPU0_RC_REFCLK0_DP";
26"TP_CPU0_RSVD_205";
27"TP_CPU0_RSVD_204";
28"TP_CPU0_RSVD_283";
29"TP_CPU0_RSVD_286";
30"TP_CPU0_RSVD_228";
31"TP_CPU0_RSVD_236";
32"TP_CPU0_RSVD_233";
33"TP_CPU0_RSVD_232";
34"TP_CPU0_RSVD_231";
35"FM_CPU0_RC_ERROR_N";
36"TP_CPU0_RSVD_256";
37"TP_CPU0_RSVD_TEST_11";
38"TP_CPU0_RSVD_253";
39"TP_CPU0_RSVD_254";
40"TP_CPU0_RSVD_303";
41"TP_CPU0_RSVD_304";
42"TP_CPU0_RSVD_287";
43"TP_CPU0_RSVD_285";
44"TP_CPU0_RSVD_284";
45"TP_CPU0_RSVD_282";
46"TP_CPU0_RSVD_275";
47"TP_CPU0_RSVD_267";
48"TP_CPU0_RSVD_266";
49"TP_CPU0_RSVD_263";
50"TP_CPU0_RSVD_261";
51"TP_CPU0_RSVD_259";
52"TP_CPU0_RSVD_194";
53"CLK_100M_CPU0_RC_REFCLK0_DN";
54"TP_CPU0_RSVD_198";
55"TP_CPU0_RSVD_199";
56"TP_CPU0_RSVD_TEST_4";
57"TP_CPU0_RSVD_TEST_3";
58"PD_CPU0_RSVD_TEST_2";
59"PD_CPU0_RSVD_TEST_1";
60"VSENSE_P1V8MCP_CPU0_SKT_VSEN";
61"TP_CPU0_RSVD_222";
62"TP_CPU0_RSVD_241";
63"TP_CPU0_RSVD_240";
64"TP_CPU0_RSVD_239";
65"TP_CPU0_RSVD_238";
66"TP_CPU0_RSVD_237";
67"TP_CPU0_RSVD_235";
68"TP_CPU0_RSVD_234";
69"TP_CPU0_RSVD_230";
70"TP_CPU0_RSVD_229";
71"TP_CPU0_RSVD_227";
72"TP_CPU0_RSVD_226";
73"TP_CPU0_RSVD_225";
74"TP_CPU0_RSVD_224";
75"TP_CPU0_RSVD_289";
76"TP_CPU0_RSVD_260";
77"TP_CPU0_RSVD_270";
78"TP_CPU0_RSVD_269";
79"TP_CPU0_RSVD_271";
80"TP_CPU0_RSVD_273";
81"TP_CPU0_RSVD_268";
82"TP_CPU0_RSVD_290";
83"TP_CPU0_RSVD_291";
84"TP_CPU0_RSVD_292";
85"TP_CPU0_RSVD_293";
86"TP_CPU0_RSVD_274";
87"TP_CPU0_RSVD_272";
88"TP_CPU0_RSVD_276";
89"TP_CPU0_RSVD_278";
90"TP_CPU0_RSVD_280";
91"TP_CPU0_RSVD_264";
92"TP_CPU0_RSVD_262";
93"TP_CPU0_RSVD_277";
94"TP_CPU0_RSVD_279";
95"TP_CPU0_RSVD_281";
96"TP_CPU0_RSVD_242";
97"TP_CPU0_RSVD_243";
98"TP_CPU0_RSVD_244";
99"TP_CPU0_RSVD_245";
100"TP_CPU0_RSVD_246";
101"TP_CPU0_RSVD_247";
102"TP_CPU0_RSVD_249";
103"TP_CPU0_RSVD_250";
104"TP_CPU0_RSVD_251";
105"TP_CPU0_RSVD_258";
106"TP_CPU0_RSVD_265";
107"TP_CPU0_RSVD_252";
108"TP_CPU0_RSVD_299";
109"TP_CPU0_RSVD_300";
%"RES"
"2","(-300,2775)","0","mstr_discrete","I188";
;
CDS_SEC"1"
WATTAGE"1/16W"
MATERIAL"CHIP"
PACK_TYPE"0402"
TOLERANCE"1%"
VALUE"49.9"
PART_NUMBER"G21796-047"
LOCATION"R5R1"
ROOM"CPU0"
CDS_LOCATION"R5R1"
SEC"1"
CDS_LIB"mstr_discrete"
SEC_TYPE"0402";
"A"
$PN"1"59;
"B"
$PN"2"1;
%"GND"
"1","(-300,2450)","0","mstr_symbols","I189";
;
SIZE"1B"
CDS_LIB"mstr_symbols"
VOLTAGE"0.0V"
BODY_TYPE"PLUMBING"
HDL_POWER"GND";
"A\NAC"1;
%"RES"
"2","(-575,2775)","0","mstr_discrete","I190";
;
CDS_SEC"1"
WATTAGE"1/16W"
MATERIAL"CHIP"
PACK_TYPE"0402"
TOLERANCE"1%"
VALUE"49.9"
PART_NUMBER"G21796-047"
LOCATION"R5P4"
ROOM"CPU0"
CDS_LOCATION"R5P4"
SEC"1"
CDS_LIB"mstr_discrete"
SEC_TYPE"0402";
"A"
$PN"1"58;
"B"
$PN"2"1;
%"VCC_CORE"
"1","(-1100,2325)","0","mstr_symbols","I202";
;
HDL_POWER"PVCCMCP_CPU0"
CDS_LIB"mstr_symbols";
"A"2;
%"VCC_CORE"
"1","(-7300,4475)","0","mstr_symbols","I203";
;
HDL_POWER"P1V8_MCP_CPU0"
CDS_LIB"mstr_symbols";
"A"3;
%"SKX_EXT_B"
"2","(-4150,2550)","0","chpset_lib","I204";
;
CDS_SEC"2"
MATERIAL"IC"
PART_NUMBER"TBD"
LOCATION"U5D1"
ROOM"CPU0"
CDS_LOCATION"U5D1"
SEC"2"
SEC_TYPE"BGA1"
CDS_LIB"chpset_lib"
PACK_TYPE"BGA1";
"TEST_5"
$PN"AN14"14;
"TEST_4"
$PN"AN12"56;
"TEST_3"
$PN"AM13"57;
"TEST_2"
$PN"AG46"58;
"TEST_11"
$PN"AY13"37;
"TEST_1"
$PN"AF45"59;
"RSVD<194>"
$PN"AP61"52;
"RSVD<195>"
$PN"AP27"53;
"RSVD<196>"
$PN"AP25"2;
"RSVD<197>"
$PN"AP23"2;
"RSVD<198>"
$PN"AN62"54;
"RSVD<199>"
$PN"AN60"55;
"RSVD<200>"
$PN"AN26"2;
"RSVD<201>"
$PN"AN24"2;
"RSVD<202>"
$PN"AN22"2;
"RSVD<203>"
$PN"AN18"2;
"RSVD<204>"
$PN"AM61"27;
"RSVD<205>"
$PN"AM59"26;
"RSVD<206>"
$PN"AM27"25;
"RSVD<207>"
$PN"AM25"2;
"RSVD<208>"
$PN"AM23"24;
"RSVD<209>"
$PN"AM21"2;
"RSVD<210>"
$PN"AL62"23;
"RSVD<211>"
$PN"AL60"7;
"RSVD<212>"
$PN"AL58"16;
"RSVD<213>"
$PN"AL26"17;
"RSVD<214>"
$PN"AL22"18;
"RSVD<215>"
$PN"AL20"22;
"RSVD<216>"
$PN"AK69"20;
"RSVD<217>"
$PN"AK61"10;
"RSVD<218>"
$PN"AK59"11;
"RSVD<219>"
$PN"AK57"5;
"RSVD<220>"
$PN"AK27"13;
"RSVD<221>"
$PN"AK21"60;
"RSVD<222>"
$PN"AJ70"61;
"RSVD<223>"
$PN"AJ62"8;
"RSVD<224>"
$PN"AJ60"74;
"RSVD<225>"
$PN"AJ58"73;
"RSVD<226>"
$PN"AJ56"72;
"RSVD<227>"
$PN"AJ20"71;
"RSVD<228>"
$PN"AH73"30;
"RSVD<229>"
$PN"AH71"70;
"RSVD<230>"
$PN"AH57"69;
"RSVD<231>"
$PN"AH55"34;
"RSVD<232>"
$PN"AH19"33;
"RSVD<233>"
$PN"AH15"32;
"RSVD<234>"
$PN"AG72"68;
"RSVD<235>"
$PN"AG56"67;
"RSVD<236>"
$PN"AG54"31;
"RSVD<237>"
$PN"AG52"66;
"RSVD<238>"
$PN"AG50"65;
"RSVD<239>"
$PN"AG48"64;
"RSVD<240>"
$PN"AG20"63;
"RSVD<241>"
$PN"AF71"62;
"RSVD<242>"
$PN"AF53"96;
"RSVD<243>"
$PN"AF51"97;
"RSVD<244>"
$PN"AF49"98;
"RSVD<245>"
$PN"AF47"99;
"RSVD<246>"
$PN"AF19"100;
"RSVD<247>"
$PN"AE72"101;
"RSVD<248>"
$PN"AE52"6;
"RSVD<249>"
$PN"AE50"102;
"RSVD<250>"
$PN"AE48"103;
"RSVD<251>"
$PN"AE46"104;
"RSVD<252>"
$PN"AD51"107;
"RSVD<253>"
$PN"AD49"38;
"RSVD<254>"
$PN"AD47"39;
"RSVD<256>"
$PN"Y65"36;
"RSVD<257>"
$PN"Y23"35;
"RSVD<258>"
$PN"W66"105;
"RSVD<259>"
$PN"V67"51;
"RSVD<260>"
$PN"V65"76;
"RSVD<261>"
$PN"U66"50;
"RSVD<262>"
$PN"T67"92;
"RSVD<263>"
$PN"R66"49;
"RSVD<264>"
$PN"R62"91;
"RSVD<265>"
$PN"P65"106;
"RSVD<266>"
$PN"M63"48;
"RSVD<267>"
$PN"K61"47;
"RSVD<268>"
$PN"J62"81;
"RSVD<269>"
$PN"J46"78;
"RSVD<270>"
$PN"H85"77;
"RSVD<271>"
$PN"H83"79;
"RSVD<272>"
$PN"H1"87;
"RSVD<273>"
$PN"G84"80;
"RSVD<274>"
$PN"G64"86;
"RSVD<275>"
$PN"G2"46;
"RSVD<276>"
$PN"F83"88;
"RSVD<277>"
$PN"F65"93;
"RSVD<278>"
$PN"F23"89;
"RSVD<279>"
$PN"F3"94;
"RSVD<280>"
$PN"E84"90;
"RSVD<281>"
$PN"E24"95;
"RSVD<282>"
$PN"E4"45;
"RSVD<283>"
$PN"E2"28;
"RSVD<284>"
$PN"D83"44;
"RSVD<285>"
$PN"D65"43;
"RSVD<286>"
$PN"D17"29;
"RSVD<287>"
$PN"D5"42;
"RSVD<288>"
$PN"C82"4;
"RSVD<289>"
$PN"C24"75;
"RSVD<290>"
$PN"C18"82;
"RSVD<291>"
$PN"C6"83;
"RSVD<292>"
$PN"B81"84;
"RSVD<293>"
$PN"B77"85;
"RSVD<294>"
$PN"B17"3;
"RSVD<295>"
$PN"B15"3;
"RSVD<296>"
$PN"B13"3;
"RSVD<298>"
$PN"B7"9;
"RSVD<299>"
$PN"B3"108;
"RSVD<300>"
$PN"A24"109;
"RSVD<301>"
$PN"A16"3;
"RSVD<302>"
$PN"A14"3;
"RSVD<303>"
$PN"A6"40;
"RSVD<304>"
$PN"A4"41;
"PWR_DEBUG_N"
$PN"AP17"21;
"FIVR_FAULT"
$PN"AU14"12;
"DMIMODE_OVERRIDE"
$PN"AW12"19;
"DEBUG_EN_N"
$PN"AV21"15;
END.
